# T6G (Grand Teton) — schematic parts with pin connectivity, parts 2629–2646 of 8303; source: Cadence DE-HDL packaged netlist (pstxprt.dat, pstxnet.dat, pstchip.dat)

J69  SCONN288_DDR506112002KQ  IO  pkg DDR288S_1-1VXC  page 93
  1  VIN_BULK0  POWER  = P12V_MEM_CPU0
  2  RFU0  TRI  = NC
  3  VIN_MGMT  POWER  = P3V3_AUX
  4  HSCL  IN  = I3C_SPD_DDRH_CPU0_SCL
  5  HSDA  BI  = I3C_SPD_DDRH_CPU0_SDA
  6  VSS0  POWER  = GND
  7  DQ0_A  BI  = M_H_CPU0_SA_DQ<0>
  8  VSS1  POWER  = GND
  9  DQ1_A  BI  = M_H_CPU0_SA_DQ<1>
  10  VSS2  POWER  = GND
  11  DQS0_A_T  BI  = M_H_CPU0_SA_DQS_DP<0>
  12  DQS0_A_C  BI  = M_H_CPU0_SA_DQS_DN<0>
  13  VSS3  POWER  = GND
  14  DQ4_A  BI  = M_H_CPU0_SA_DQ<4>
  15  VSS4  POWER  = GND
  16  DQ5_A  BI  = M_H_CPU0_SA_DQ<5>
  17  VSS5  POWER  = GND
  18  DQ8_A  BI  = M_H_CPU0_SA_DQ<8>
  19  VSS6  POWER  = GND
  20  DQ9_A  BI  = M_H_CPU0_SA_DQ<9>
  21  VSS7  POWER  = GND
  22  DQS1_A_T  BI  = M_H_CPU0_SA_DQS_DP<1>
  23  DQS1_A_C  BI  = M_H_CPU0_SA_DQS_DN<1>
  24  VSS8  POWER  = GND
  25  DQ12_A  BI  = M_H_CPU0_SA_DQ<12>
  26  VSS9  POWER  = GND
  27  DQ13_A  BI  = M_H_CPU0_SA_DQ<13>
  28  VSS10  POWER  = GND
  29  DQ16_A  BI  = M_H_CPU0_SA_DQ<16>
  30  VSS11  POWER  = GND
  31  DQ17_A  BI  = M_H_CPU0_SA_DQ<17>
  32  VSS12  POWER  = GND
  33  DQS2_A_T  BI  = M_H_CPU0_SA_DQS_DP<2>
  34  DQS2_A_C  BI  = M_H_CPU0_SA_DQS_DN<2>
  35  VSS13  POWER  = GND
  36  DQ20_A  BI  = M_H_CPU0_SA_DQ<20>
  37  VSS14  POWER  = GND
  38  DQ21_A  BI  = M_H_CPU0_SA_DQ<21>
  39  VSS15  POWER  = GND
  40  DQ24_A  BI  = M_H_CPU0_SA_DQ<24>
  41  VSS16  POWER  = GND
  42  DQ25_A  BI  = M_H_CPU0_SA_DQ<25>
  43  VSS17  POWER  = GND
  44  DQS3_A_T  BI  = M_H_CPU0_SA_DQS_DP<3>
  45  DQS3_A_C  BI  = M_H_CPU0_SA_DQS_DN<3>
  46  VSS18  POWER  = GND
  47  DQ28_A  BI  = M_H_CPU0_SA_DQ<28>
  48  VSS19  POWER  = GND
  49  DQ29_A  BI  = M_H_CPU0_SA_DQ<29>
  50  VSS20  POWER  = GND
  51  CB0_A  BI  = M_H_CPU0_SA_CB<0>
  52  VSS21  POWER  = GND
  53  CB1_A  BI  = M_H_CPU0_SA_CB<1>
  54  VSS22  POWER  = GND
  55  DQS4_A_T  BI  = M_H_CPU0_SA_DQS_DP<4>
  56  DQS4_A_C  BI  = M_H_CPU0_SA_DQS_DN<4>
  57  VSS23  POWER  = GND
  58  CB4_A  BI  = M_H_CPU0_SA_CB<4>
  59  VSS24  POWER  = GND
  60  CB5_A  BI  = M_H_CPU0_SA_CB<5>
  61  VSS25  POWER  = GND
  62  ALERT_N  OUT  = M_H_CPU0_ALERT_N
  63  VSS26  POWER  = GND
  64  CS0_A_N  IN  = M_H_CPU0_SA_CS_N<0>
  65  VSS27  POWER  = GND
  66  CA0_A  IN  = M_H_CPU0_SA_CA<0>
  67  VSS28  POWER  = GND
  68  CA2_A  IN  = M_H_CPU0_SA_CA<2>
  69  VSS29  POWER  = GND
  70  CA4_A  IN  = M_H_CPU0_SA_CA<4>
  71  VSS30  POWER  = GND
  72  CA6_A  IN  = M_H_CPU0_SA_CA<6>
  73  VSS31  POWER  = GND
  74  PAR_A  IN  = M_H_CPU0_SA_PAR
  75  VSS32  POWER  = GND
  76  CA0_B  IN  = M_H_CPU0_SB_CA<0>
  77  VSS33  POWER  = GND
  78  CA2_B  IN  = M_H_CPU0_SB_CA<2>
  79  VSS34  POWER  = GND
  80  CA4_B  IN  = M_H_CPU0_SB_CA<4>
  81  VSS35  POWER  = GND
  82  CA6_B  IN  = M_H_CPU0_SB_CA<6>
  83  VSS36  POWER  = GND
  84  CS0_B_N  IN  = M_H_CPU0_SB_CS_N<0>
  85  VSS37  POWER  = GND
  86  \lbd||rsp_a_n\  OUT  = M_H_CPU0_SA_RSP<0>
  87  \lbs||rsp_b_n\  OUT  = M_H_CPU0_SB_RSP<0>
  88  VSS38  POWER  = GND
  89  CB4_B  BI  = M_H_CPU0_SB_CB<4>
  90  VSS39  POWER  = GND
  91  CB5_B  BI  = M_H_CPU0_SB_CB<5>
  92  VSS40  POWER  = GND
  93  \dqs9_b_t||tdqs9_b_t||dbi4_b_n\  BI  = M_H_CPU0_SB_DQS_DP<9>
  94  \dqs9_b_c||tdqs9_b_c\  BI  = M_H_CPU0_SB_DQS_DN<9>
  95  VSS41  POWER  = GND
  96  CB0_B  BI  = M_H_CPU0_SB_CB<0>
  97  VSS42  POWER  = GND
  98  CB1_B  BI  = M_H_CPU0_SB_CB<1>
  99  VSS43  POWER  = GND
  100  DQ0_B  BI  = M_H_CPU0_SB_DQ<0>
  101  VSS44  POWER  = GND
  102  DQ1_B  BI  = M_H_CPU0_SB_DQ<1>
  103  VSS45  POWER  = GND
  104  DQS0_B_T  BI  = M_H_CPU0_SB_DQS_DP<0>
  105  DQS0_B_C  BI  = M_H_CPU0_SB_DQS_DN<0>
  106  VSS46  POWER  = GND
  107  DQ4_B  BI  = M_H_CPU0_SB_DQ<4>
  108  VSS47  POWER  = GND
  109  DQ5_B  BI  = M_H_CPU0_SB_DQ<5>
  110  VSS48  POWER  = GND
  111  DQ8_B  BI  = M_H_CPU0_SB_DQ<8>
  112  VSS49  POWER  = GND
  113  DQ9_B  BI  = M_H_CPU0_SB_DQ<9>
  114  VSS50  POWER  = GND
  115  DQS1_B_T  BI  = M_H_CPU0_SB_DQS_DP<1>
  116  DQS1_B_C  BI  = M_H_CPU0_SB_DQS_DN<1>
  117  VSS51  POWER  = GND
  118  DQ12_B  BI  = M_H_CPU0_SB_DQ<12>
  119  VSS52  POWER  = GND
  120  DQ13_B  BI  = M_H_CPU0_SB_DQ<13>
  121  VSS53  POWER  = GND
  122  DQ16_B  BI  = M_H_CPU0_SB_DQ<16>
  123  VSS54  POWER  = GND
  124  DQ17_B  BI  = M_H_CPU0_SB_DQ<17>
  125  VSS55  POWER  = GND
  126  DQS2_B_T  BI  = M_H_CPU0_SB_DQS_DP<2>
  127  DQS2_B_C  BI  = M_H_CPU0_SB_DQS_DN<2>
  128  VSS56  POWER  = GND
  129  DQ20_B  BI  = M_H_CPU0_SB_DQ<20>
  130  VSS57  POWER  = GND
  131  DQ21_B  BI  = M_H_CPU0_SB_DQ<21>
  132  VSS58  POWER  = GND
  133  DQ24_B  BI  = M_H_CPU0_SB_DQ<24>
  134  VSS59  POWER  = GND
  135  DQ25_B  BI  = M_H_CPU0_SB_DQ<25>
  136  VSS60  POWER  = GND
  137  DQS3_B_T  BI  = M_H_CPU0_SB_DQS_DP<3>
  138  DQS3_B_C  BI  = M_H_CPU0_SB_DQS_DN<3>
  139  VSS61  POWER  = GND
  140  DQ28_B  BI  = M_H_CPU0_SB_DQ<28>
  141  VSS62  POWER  = GND
  142  DQ29_B  BI  = M_H_CPU0_SB_DQ<29>
  143  VSS63  POWER  = GND
  144  RFU1  TRI  = NC
  145  VIN_BULK1  POWER  = P12V_MEM_CPU0
  146  VIN_BULK2  POWER  = P12V_MEM_CPU0
  147  \pwr_good||fail_n\  BI  = PWRGD_CHH_CPU0_DIMM
  148  HAS  IN  = PD_CHH_CPU0_DIMM_SAA
  149  RFU2  TRI  = NC
  150  RFU3  TRI  = NC
  151  VSS64  POWER  = GND
  152  DQ2_A  BI  = M_H_CPU0_SA_DQ<2>
  153  VSS65  POWER  = GND
  154  DQ3_A  BI  = M_H_CPU0_SA_DQ<3>
  155  VSS66  POWER  = GND
  156  \dqs5_a_c||tdqs5_a_c||dqs5_a_t||tdqs5_a_t\  BI  = M_H_CPU0_SA_DQS_DN<5>
  157  \dqs5_a_t||tdqs5_a_t\  BI  = M_H_CPU0_SA_DQS_DP<5>
  158  VSS67  POWER  = GND
  159  DQ6_A  BI  = M_H_CPU0_SA_DQ<6>
  160  VSS68  POWER  = GND
  161  DQ7_A  BI  = M_H_CPU0_SA_DQ<7>
  162  VSS69  POWER  = GND
  163  DQ10_A  BI  = M_H_CPU0_SA_DQ<10>
  164  VSS70  POWER  = GND
  165  DQ11_A  BI  = M_H_CPU0_SA_DQ<11>
  166  VSS71  POWER  = GND
  167  \dqs6_a_c||tdqs6_a_c||dqs6_a_t||tdqs6_a_t\  BI  = M_H_CPU0_SA_DQS_DN<6>
  168  \dqs6_a_t||tdqs6_a_t\  BI  = M_H_CPU0_SA_DQS_DP<6>
  169  VSS72  POWER  = GND
  170  DQ14_A  BI  = M_H_CPU0_SA_DQ<14>
  171  VSS73  POWER  = GND
  172  DQ15_A  BI  = M_H_CPU0_SA_DQ<15>
  173  VSS74  POWER  = GND
  174  DQ18_A  BI  = M_H_CPU0_SA_DQ<18>
  175  VSS75  POWER  = GND
  176  DQ19_A  BI  = M_H_CPU0_SA_DQ<19>
  177  VSS76  POWER  = GND
  178  \dqs7_a_c||tdqs7_a_c\  BI  = M_H_CPU0_SA_DQS_DN<7>
  179  \dqs7_a_t||tdqs7_a_t\  BI  = M_H_CPU0_SA_DQS_DP<7>
  180  VSS77  POWER  = GND
  181  DQ22_A  BI  = M_H_CPU0_SA_DQ<22>
  182  VSS78  POWER  = GND
  183  DQ23_A  BI  = M_H_CPU0_SA_DQ<23>
  184  VSS79  POWER  = GND
  185  DQ26_A  BI  = M_H_CPU0_SA_DQ<26>
  186  VSS80  POWER  = GND
  187  DQ27_A  BI  = M_H_CPU0_SA_DQ<27>
  188  VSS81  POWER  = GND
  189  \dqs8_a_c||tdqs8_a_c\  BI  = M_H_CPU0_SA_DQS_DN<8>
  190  \dqs8_a_t||tdqs8_a_t\  BI  = M_H_CPU0_SA_DQS_DP<8>
  191  VSS82  POWER  = GND
  192  DQ30_A  BI  = M_H_CPU0_SA_DQ<30>
  193  VSS83  POWER  = GND
  194  DQ31_A  BI  = M_H_CPU0_SA_DQ<31>
  195  VSS84  POWER  = GND
  196  CB2_A  BI  = M_H_CPU0_SA_CB<2>
  197  VSS85  POWER  = GND
  198  CB3_A  BI  = M_H_CPU0_SA_CB<3>
  199  VSS86  POWER  = GND
  200  \dqs9_a_c||tdqs9_a_c\  BI  = M_H_CPU0_SA_DQS_DN<9>
  201  \dqs9_a_t||tdqs9_a_t\  BI  = M_H_CPU0_SA_DQS_DP<9>
  202  VSS87  POWER  = GND
  203  CB6_A  BI  = M_H_CPU0_SA_CB<6>
  204  VSS88  POWER  = GND
  205  CB7_A  BI  = M_H_CPU0_SA_CB<7>
  206  VSS89  POWER  = GND
  207  RESET_N  IN  = M_H_CPU0_RESET_N
  208  VSS90  POWER  = GND
  209  CS1_A_N  IN  = M_H_CPU0_SA_CS_N<1>
  210  VSS91  POWER  = GND
  211  CA1_A  IN  = M_H_CPU0_SA_CA<1>
  212  VSS92  POWER  = GND
  213  CA3_A  IN  = M_H_CPU0_SA_CA<3>
  214  VSS93  POWER  = GND
  215  CA5_A  IN  = M_H_CPU0_SA_CA<5>
  216  VSS94  POWER  = GND
  217  CK_T  IN  = M_H_CPU0_CLK_DP<0>
  218  CK_C  IN  = M_H_CPU0_CLK_DN<0>
  219  VSS95  POWER  = GND
  220  RFU4  TRI  = NC
  221  CA1_B  IN  = M_H_CPU0_SB_CA<1>
  222  VSS96  POWER  = GND
  223  CA3_B  IN  = M_H_CPU0_SB_CA<3>
  224  VSS97  POWER  = GND
  225  CA5_B  IN  = M_H_CPU0_SB_CA<5>
  226  VSS98  POWER  = GND
  227  PAR_B  IN  = M_H_CPU0_SB_PAR
  228  VSS99  POWER  = GND
  229  CS1_B_N  IN  = M_H_CPU0_SB_CS_N<1>
  230  VSS100  POWER  = GND
  231  RFU5  TRI  = NC
  232  RFU6  TRI  = NC
  233  VSS101  POWER  = GND
  234  CB6_B  BI  = M_H_CPU0_SB_CB<6>
  235  VSS102  POWER  = GND
  236  CB7_B  BI  = M_H_CPU0_SB_CB<7>
  237  VSS103  POWER  = GND
  238  DQS4_B_C  BI  = M_H_CPU0_SB_DQS_DN<4>
  239  DQS4_B_T  BI  = M_H_CPU0_SB_DQS_DP<4>
  240  VSS104  POWER  = GND
  241  CB2_B  BI  = M_H_CPU0_SB_CB<2>
  242  VSS105  POWER  = GND
  243  CB3_B  BI  = M_H_CPU0_SB_CB<3>
  244  VSS106  POWER  = GND
  245  DQ2_B  BI  = M_H_CPU0_SB_DQ<2>
  246  VSS107  POWER  = GND
  247  DQ3_B  BI  = M_H_CPU0_SB_DQ<3>
  248  VSS108  POWER  = GND
  249  \dqs5_b_c||tdqs5_b_c\  BI  = M_H_CPU0_SB_DQS_DN<5>
  250  \dqs5_b_t||tdqs5_b_t\  BI  = M_H_CPU0_SB_DQS_DP<5>
  251  VSS109  POWER  = GND
  252  DQ6_B  BI  = M_H_CPU0_SB_DQ<6>
  253  VSS110  POWER  = GND
  254  DQ7_B  BI  = M_H_CPU0_SB_DQ<7>
  255  VSS111  POWER  = GND
  256  DQ10_B  BI  = M_H_CPU0_SB_DQ<10>
  257  VSS112  POWER  = GND
  258  DQ11_B  BI  = M_H_CPU0_SB_DQ<11>
  259  VSS113  POWER  = GND
  260  \dqs6_b_c||tdqs6_b_c\  BI  = M_H_CPU0_SB_DQS_DN<6>
  261  \dqs6_b_t||tdqs6_b_t\  BI  = M_H_CPU0_SB_DQS_DP<6>
  262  VSS114  POWER  = GND
  263  DQ14_B  BI  = M_H_CPU0_SB_DQ<14>
  264  VSS115  POWER  = GND
  265  DQ15_B  BI  = M_H_CPU0_SB_DQ<15>
  266  VSS116  POWER  = GND
  267  DQ18_B  BI  = M_H_CPU0_SB_DQ<18>
  268  VSS117  POWER  = GND
  269  DQ19_B  BI  = M_H_CPU0_SB_DQ<19>
  270  VSS118  POWER  = GND
  271  \dqs7_b_c||tdqs7_b_c\  BI  = M_H_CPU0_SB_DQS_DN<7>
  272  \dqs7_b_t||tdqs7_b_t\  BI  = M_H_CPU0_SB_DQS_DP<7>
  273  VSS119  POWER  = GND
  274  DQ22_B  BI  = M_H_CPU0_SB_DQ<22>
  275  VSS120  POWER  = GND
  276  DQ23_B  BI  = M_H_CPU0_SB_DQ<23>
  277  VSS121  POWER  = GND
  278  DQ26_B  BI  = M_H_CPU0_SB_DQ<26>
  279  VSS122  POWER  = GND
  280  DQ27_B  BI  = M_H_CPU0_SB_DQ<27>
  281  VSS123  POWER  = GND
  282  \dqs8_b_c||tdqs8_b_c\  BI  = M_H_CPU0_SB_DQS_DN<8>
  283  \dqs8_b_t||tdqs8_b_t\  BI  = M_H_CPU0_SB_DQS_DP<8>
  284  VSS124  POWER  = GND
  285  DQ30_B  BI  = M_H_CPU0_SB_DQ<30>
  286  VSS125  POWER  = GND
  287  DQ31_B  BI  = M_H_CPU0_SB_DQ<31>
  288  VSS126  POWER  = GND
  G1  G1  POWER  = GND
  G2  G2  POWER  = GND
  G3  G3  POWER  = GND

J70  PICOPROBE_BXA  DELTA-L 4.0 EMPTY  pkg TRIANG_LAUNCH_3PXB  page 229
  1  \1_p\  POWER  = DELTA_L_85_5INCH_BOT_DN
  2  \2_n\  POWER  = DELTA_L_85_5INCH_BOT_DP
  3  \3_g\  POWER  = DELTA_L_GND_1

J71  PICOPROBE_BXA  DELTA-L 4.0 EMPTY  pkg TRIANG_LAUNCH_3PXB  page 229
  1  \1_p\  POWER  = DELTA_L_85_5INCH_IN1_DN
  2  \2_n\  POWER  = DELTA_L_85_5INCH_IN1_DP
  3  \3_g\  POWER  = DELTA_L_GND_1

J72  PICOPROBE_BXA  DELTA-L 4.0 EMPTY  pkg TRIANG_LAUNCH_3PXB  page 229
  1  \1_p\  POWER  = DELTA_L_85_5INCH_IN2_DN
  2  \2_n\  POWER  = DELTA_L_85_5INCH_IN2_DP
  3  \3_g\  POWER  = DELTA_L_GND_1

J73  PICOPROBE_BXA  DELTA-L 4.0 EMPTY  pkg TRIANG_LAUNCH_3PXB  page 229
  1  \1_p\  POWER  = DELTA_L_85_5INCH_IN3_DN
  2  \2_n\  POWER  = DELTA_L_85_5INCH_IN3_DP
  3  \3_g\  POWER  = DELTA_L_GND_1

J74  PICOPROBE_BXA  DELTA-L 4.0 EMPTY  pkg TRIANG_LAUNCH_3PXB  page 229
  1  \1_p\  POWER  = DELTA_L_85_5INCH_IN4_DN
  2  \2_n\  POWER  = DELTA_L_85_5INCH_IN4_DP
  3  \3_g\  POWER  = DELTA_L_GND_1

J75  PICOPROBE_BXA  DELTA-L 4.0 EMPTY  pkg TRIANG_LAUNCH_3PXB  page 229
  1  \1_p\  POWER  = DELTA_L_85_10INCH_TOP_DP
  2  \2_n\  POWER  = DELTA_L_85_10INCH_TOP_DN
  3  \3_g\  POWER  = DELTA_L_GND_1

J76  PICOPROBE_BXA  DELTA-L 4.0 EMPTY  pkg TRIANG_LAUNCH_3PXB  page 229
  1  \1_p\  POWER  = DELTA_L_85_10INCH_BOT_DP
  2  \2_n\  POWER  = DELTA_L_85_10INCH_BOT_DN
  3  \3_g\  POWER  = DELTA_L_GND_1

J77  PICOPROBE_BXA  DELTA-L 4.0 EMPTY  pkg TRIANG_LAUNCH_3PXB  page 229
  1  \1_p\  POWER  = DELTA_L_85_10INCH_IN1_DP
  2  \2_n\  POWER  = DELTA_L_85_10INCH_IN1_DN
  3  \3_g\  POWER  = DELTA_L_GND_1

J78  PICOPROBE_BXA  DELTA-L 4.0 EMPTY  pkg TRIANG_LAUNCH_3PXB  page 229
  1  \1_p\  POWER  = DELTA_L_85_10INCH_IN2_DP
  2  \2_n\  POWER  = DELTA_L_85_10INCH_IN2_DN
  3  \3_g\  POWER  = DELTA_L_GND_1

J79  PICOPROBE_BXA  DELTA-L 4.0 EMPTY  pkg TRIANG_LAUNCH_3PXB  page 229
  1  \1_p\  POWER  = DELTA_L_85_10INCH_IN3_DP
  2  \2_n\  POWER  = DELTA_L_85_10INCH_IN3_DN
  3  \3_g\  POWER  = DELTA_L_GND_1

J80  PICOPROBE_BXA  DELTA-L 4.0 EMPTY  pkg TRIANG_LAUNCH_3PXB  page 229
  1  \1_p\  POWER  = DELTA_L_85_10INCH_IN4_DP
  2  \2_n\  POWER  = DELTA_L_85_10INCH_IN4_DN
  3  \3_g\  POWER  = DELTA_L_GND_1

J81  PICOPROBE_BXA  DELTA-L 4.0 EMPTY  pkg TRIANG_LAUNCH_3PXB  page 229
  1  \1_p\  POWER  = DELTA_L_85_10INCH_TOP_DN
  2  \2_n\  POWER  = DELTA_L_85_10INCH_TOP_DP
  3  \3_g\  POWER  = DELTA_L_GND_1

J82  PICOPROBE_BXA  DELTA-L 4.0 EMPTY  pkg TRIANG_LAUNCH_3PXB  page 229
  1  \1_p\  POWER  = DELTA_L_85_10INCH_BOT_DN
  2  \2_n\  POWER  = DELTA_L_85_10INCH_BOT_DP
  3  \3_g\  POWER  = DELTA_L_GND_1

J83  PICOPROBE_BXA  DELTA-L 4.0 EMPTY  pkg TRIANG_LAUNCH_3PXB  page 229
  1  \1_p\  POWER  = DELTA_L_85_10INCH_IN1_DN
  2  \2_n\  POWER  = DELTA_L_85_10INCH_IN1_DP
  3  \3_g\  POWER  = DELTA_L_GND_1

J84  PICOPROBE_BXA  DELTA-L 4.0 EMPTY  pkg TRIANG_LAUNCH_3PXB  page 229
  1  \1_p\  POWER  = DELTA_L_85_10INCH_IN2_DN
  2  \2_n\  POWER  = DELTA_L_85_10INCH_IN2_DP
  3  \3_g\  POWER  = DELTA_L_GND_1

J85  PICOPROBE_BXA  DELTA-L 4.0 EMPTY  pkg TRIANG_LAUNCH_3PXB  page 229
  1  \1_p\  POWER  = DELTA_L_85_10INCH_IN3_DN
  2  \2_n\  POWER  = DELTA_L_85_10INCH_IN3_DP
  3  \3_g\  POWER  = DELTA_L_GND_1

J86  PICOPROBE_BXA  DELTA-L 4.0 EMPTY  pkg TRIANG_LAUNCH_3PXB  page 229
  1  \1_p\  POWER  = DELTA_L_85_10INCH_IN4_DN
  2  \2_n\  POWER  = DELTA_L_85_10INCH_IN4_DP
  3  \3_g\  POWER  = DELTA_L_GND_1
